(kicad_pcb
	(version 20241229)
	(generator "pcbnew")
	(generator_version "9.0")
	(general
		(thickness 1.59)
		(legacy_teardrops no)
	)
	(paper "A3")
	(title_block
		(title "usb-c-power-adapter")
		(date "2025-06-24")
		(rev "1.1.2")
		(company "Antmicro")
		(comment 9 "footprints 55-58 of 122")
	)
	(layers
		(0 "F.Cu" signal)
		(4 "In1.Cu" signal)
		(6 "In2.Cu" signal)
		(2 "B.Cu" signal)
		(9 "F.Adhes" user "F.Adhesive")
		(11 "B.Adhes" user "B.Adhesive")
		(13 "F.Paste" user)
		(15 "B.Paste" user)
		(5 "F.SilkS" user "F.Silkscreen")
		(7 "B.SilkS" user "B.Silkscreen")
		(1 "F.Mask" user)
		(3 "B.Mask" user)
		(17 "Dwgs.User" user "User.Drawings")
		(19 "Cmts.User" user "User.Comments")
		(21 "Eco1.User" user "User.Eco1")
		(23 "Eco2.User" user "User.Eco2")
		(25 "Edge.Cuts" user)
		(27 "Margin" user)
		(31 "F.CrtYd" user "F.Courtyard")
		(29 "B.CrtYd" user "B.Courtyard")
		(35 "F.Fab" user)
		(33 "B.Fab" user)
	)
	(footprint "antmicro-footprints:R_0402_1005Metric"
		(layer "F.Cu")
		(at 92.776 80.3 90)
		(descr "Resistor SMD 0402")
		(tags "resistor SMD 0402")
		(property "Reference" "R20"
			(at 1.05 10.05 0)
			(layer "B.SilkS")
			(effects
				(font
					(size 0.7 0.7)
					(thickness 0.15)
				)
				(justify left bottom mirror)
			)
		)
		(property "Value" "R_1k_0402"
			(at -1.011843 1.772047 90)
			(layer "F.Fab")
			(effects
				(font
					(size 0.7 0.7)
					(thickness 0.15)
				)
				(justify left bottom)
			)
		)
		(property "Datasheet" "https://www.bourns.com/docs/product-datasheets/cr.pdf"
			(at 0 0 90)
			(layer "F.Fab")
			(hide yes)
			(effects
				(font
					(size 1.27 1.27)
					(thickness 0.15)
				)
			)
		)
		(property "Description" "SMD Chip Resistor, 1 kohm, ± 1%, 63 mW, 0402 [1005 Metric], Thick Film, General Purpose"
			(at 0 0 90)
			(layer "F.Fab")
			(hide yes)
			(effects
				(font
					(size 1.27 1.27)
					(thickness 0.15)
				)
			)
		)
		(property "MPN" "CR0402-FX-1001GLF"
			(at 0 0 90)
			(unlocked yes)
			(layer "F.Fab")
			(hide yes)
			(effects
				(font
					(size 1 1)
					(thickness 0.15)
				)
			)
		)
		(property "Manufacturer" "Bourns"
			(at 0 0 90)
			(unlocked yes)
			(layer "F.Fab")
			(hide yes)
			(effects
				(font
					(size 1 1)
					(thickness 0.15)
				)
			)
		)
		(property "License" "Apache-2.0"
			(at 0 0 90)
			(unlocked yes)
			(layer "F.Fab")
			(hide yes)
			(effects
				(font
					(size 1 1)
					(thickness 0.15)
				)
			)
		)
		(property "Author" "Antmicro"
			(at 0 0 90)
			(unlocked yes)
			(layer "F.Fab")
			(hide yes)
			(effects
				(font
					(size 1 1)
					(thickness 0.15)
				)
			)
		)
		(property "Val" "1k"
			(at 0 0 90)
			(unlocked yes)
			(layer "F.Fab")
			(hide yes)
			(effects
				(font
					(size 1 1)
					(thickness 0.15)
				)
			)
		)
		(property "Tolerance" "1%"
			(at 0 0 90)
			(unlocked yes)
			(layer "F.Fab")
			(hide yes)
			(effects
				(font
					(size 1 1)
					(thickness 0.15)
				)
			)
		)
		(sheetname "/USB PD/")
		(sheetfile "usb_pd.kicad_sch")
		(attr smd)
		(fp_rect
			(start -0.925 -0.47)
			(end 0.925 0.47)
			(stroke
				(width 0.05)
				(type default)
			)
			(fill no)
			(layer "F.CrtYd")
		)
		(fp_rect
			(start -0.5 -0.25)
			(end 0.5 0.25)
			(stroke
				(width 0.15)
				(type solid)
			)
			(fill no)
			(layer "F.Fab")
		)
		(pad "1" smd roundrect
			(at -0.48 0 90)
			(size 0.59 0.64)
			(layers "F.Cu" "F.Mask" "F.Paste")
			(roundrect_rratio 0.25)
			(net 52 "/USB PD/VBUS_DISCH")
			(pintype "passive")
		)
		(pad "2" smd roundrect
			(at 0.48 0 90)
			(size 0.59 0.64)
			(layers "F.Cu" "F.Mask" "F.Paste")
			(roundrect_rratio 0.25)
			(net 63 "Net-(D1-C)")
			(pintype "passive")
		)
	)
	(footprint "antmicro-footprints:USON-10_2.5x1mm_P0.5mm"
		(layer "F.Cu")
		(at 86.9 68.6 90)
		(descr "USON-10 2.5x1mm_ Pitch 0.5mm")
		(tags "USON-10 2.5x1mm Pitch 0.5mm")
		(property "Reference" "U6"
			(at 0.8836 -1.1496 180)
			(layer "F.SilkS")
			(effects
				(font
					(size 0.7 0.7)
					(thickness 0.15)
				)
				(justify left bottom)
			)
		)
		(property "Value" "TPD4E02B04DQA"
			(at 0.018 2.499 90)
			(layer "F.Fab")
			(effects
				(font
					(size 0.7 0.7)
					(thickness 0.15)
				)
				(justify left bottom)
			)
		)
		(property "Datasheet" "http://www.ti.com/lit/ds/symlink/tpd4e02b04.pdf"
			(at 0 0 90)
			(layer "F.Fab")
			(hide yes)
			(effects
				(font
					(size 1.27 1.27)
					(thickness 0.15)
				)
			)
		)
		(property "Description" "TVS diode array, 12 kV, USON-10, 3.6 V, 0.33 pF"
			(at 0 0 90)
			(layer "F.Fab")
			(hide yes)
			(effects
				(font
					(size 1.27 1.27)
					(thickness 0.15)
				)
			)
		)
		(property "MPN" "TPD4E02B04DQAR"
			(at 0 0 90)
			(unlocked yes)
			(layer "F.Fab")
			(hide yes)
			(effects
				(font
					(size 1 1)
					(thickness 0.15)
				)
			)
		)
		(property "Manufacturer" "Texas Instruments"
			(at 0 0 90)
			(unlocked yes)
			(layer "F.Fab")
			(hide yes)
			(effects
				(font
					(size 1 1)
					(thickness 0.15)
				)
			)
		)
		(property "Author" "Antmicro"
			(at 0 0 90)
			(unlocked yes)
			(layer "F.Fab")
			(hide yes)
			(effects
				(font
					(size 1 1)
					(thickness 0.15)
				)
			)
		)
		(property "License" "Apache-2.0"
			(at 0 0 90)
			(unlocked yes)
			(layer "F.Fab")
			(hide yes)
			(effects
				(font
					(size 1 1)
					(thickness 0.15)
				)
			)
		)
		(property ki_fp_filters "USON*2.5x1.0mm*P0.5mm*")
		(sheetname "/USB PD/")
		(sheetfile "usb_pd.kicad_sch")
		(attr smd)
		(fp_line
			(start 0.498 -1.401)
			(end -0.5 -1.401)
			(stroke
				(width 0.15)
				(type solid)
			)
			(layer "F.SilkS")
		)
		(fp_line
			(start 0.498 1.398)
			(end -0.5 1.398)
			(stroke
				(width 0.15)
				(type solid)
			)
			(layer "F.SilkS")
		)
		(fp_circle
			(center -0.68 -1.27)
			(end -0.63 -1.27)
			(stroke
				(width 0.15)
				(type solid)
			)
			(fill yes)
			(layer "F.SilkS")
		)
		(fp_rect
			(start -0.8 -1.5)
			(end 0.8 1.499)
			(stroke
				(width 0.05)
				(type solid)
			)
			(fill no)
			(layer "F.CrtYd")
		)
		(fp_line
			(start 0.498 -1.25)
			(end -0.25 -1.25)
			(stroke
				(width 0.15)
				(type solid)
			)
			(layer "F.Fab")
		)
		(fp_line
			(start 0.498 -1.25)
			(end 0.498 1.249)
			(stroke
				(width 0.15)
				(type solid)
			)
			(layer "F.Fab")
		)
		(fp_line
			(start -0.25 -1.25)
			(end -0.5 -1)
			(stroke
				(width 0.15)
				(type solid)
			)
			(layer "F.Fab")
		)
		(fp_line
			(start -0.5 -1)
			(end -0.5 1.249)
			(stroke
				(width 0.15)
				(type solid)
			)
			(layer "F.Fab")
		)
		(fp_line
			(start -0.5 1.249)
			(end 0.498 1.249)
			(stroke
				(width 0.15)
				(type solid)
			)
			(layer "F.Fab")
		)
		(pad "1" smd roundrect
			(at -0.387 -1)
			(size 0.25 0.55)
			(layers "F.Cu" "F.Mask" "F.Paste")
			(roundrect_rratio 0.25)
			(net 70 "unconnected-(U6-Pad1)_1")
			(pintype "passive+no_connect")
		)
		(pad "2" smd roundrect
			(at -0.387 -0.5)
			(size 0.25 0.55)
			(layers "F.Cu" "F.Mask" "F.Paste")
			(roundrect_rratio 0.25)
			(net 38 "/USB PD/SCL")
			(pintype "passive")
		)
		(pad "3" smd roundrect
			(at -0.387 0)
			(size 0.4 0.55)
			(layers "F.Cu" "F.Mask" "F.Paste")
			(roundrect_rratio 0.25)
			(net 2 "GND")
			(pintype "power_in")
		)
		(pad "4" smd roundrect
			(at -0.387 0.498)
			(size 0.25 0.55)
			(layers "F.Cu" "F.Mask" "F.Paste")
			(roundrect_rratio 0.25)
			(net 37 "/USB PD/SDA")
			(pintype "passive")
		)
		(pad "5" smd roundrect
			(at -0.387 0.998)
			(size 0.25 0.55)
			(layers "F.Cu" "F.Mask" "F.Paste")
			(roundrect_rratio 0.25)
			(net 61 "/USB PD/QWIIC_VCC")
			(pintype "passive")
		)
		(pad "6" smd roundrect
			(at 0.385 0.998)
			(size 0.25 0.55)
			(layers "F.Cu" "F.Mask" "F.Paste")
			(roundrect_rratio 0.25)
			(net 61 "/USB PD/QWIIC_VCC")
			(pintype "passive")
		)
		(pad "7" smd roundrect
			(at 0.385 0.498)
			(size 0.25 0.55)
			(layers "F.Cu" "F.Mask" "F.Paste")
			(roundrect_rratio 0.25)
			(net 37 "/USB PD/SDA")
			(pintype "passive")
		)
		(pad "8" smd roundrect
			(at 0.385 0)
			(size 0.4 0.55)
			(layers "F.Cu" "F.Mask" "F.Paste")
			(roundrect_rratio 0.25)
			(net 2 "GND")
			(pintype "passive")
		)
		(pad "9" smd roundrect
			(at 0.385 -0.5)
			(size 0.25 0.55)
			(layers "F.Cu" "F.Mask" "F.Paste")
			(roundrect_rratio 0.25)
			(net 38 "/USB PD/SCL")
			(pintype "passive")
		)
		(pad "10" smd roundrect
			(at 0.385 -1)
			(size 0.25 0.55)
			(layers "F.Cu" "F.Mask" "F.Paste")
			(roundrect_rratio 0.25)
			(net 62 "unconnected-(U6-Pad1)")
			(pintype "passive+no_connect")
		)
	)
	(footprint "antmicro-footprints:TP_SMD_0.75mm"
		(layer "F.Cu")
		(at 87.801 87.225)
		(property "Reference" "TP13"
			(at 0 -0.6 0)
			(layer "F.SilkS")
			(hide yes)
			(effects
				(font
					(size 0.7 0.7)
					(thickness 0.15)
				)
				(justify left bottom)
			)
		)
		(property "Value" "TP_0.75mm_SMD"
			(at 0 1.2 0)
			(layer "F.Fab")
			(effects
				(font
					(size 0.7 0.7)
					(thickness 0.15)
				)
				(justify left bottom)
			)
		)
		(property "Description" "SMT test point"
			(at 0 0 0)
			(layer "F.Fab")
			(hide yes)
			(effects
				(font
					(size 1.27 1.27)
					(thickness 0.15)
				)
			)
		)
		(property "MPN" ""
			(at 0 0 0)
			(unlocked yes)
			(layer "F.Fab")
			(hide yes)
			(effects
				(font
					(size 1 1)
					(thickness 0.15)
				)
			)
		)
		(property "Manufacturer" ""
			(at 0 0 0)
			(unlocked yes)
			(layer "F.Fab")
			(hide yes)
			(effects
				(font
					(size 1 1)
					(thickness 0.15)
				)
			)
		)
		(property "Author" "Antmicro"
			(at 0 0 0)
			(unlocked yes)
			(layer "F.Fab")
			(hide yes)
			(effects
				(font
					(size 1 1)
					(thickness 0.15)
				)
			)
		)
		(property "License" "Apache-2.0"
			(at 0 0 0)
			(unlocked yes)
			(layer "F.Fab")
			(hide yes)
			(effects
				(font
					(size 1 1)
					(thickness 0.15)
				)
			)
		)
		(sheetname "/USB PD/")
		(sheetfile "usb_pd.kicad_sch")
		(attr exclude_from_bom)
		(fp_circle
			(center 0 0)
			(end 0.475 0)
			(stroke
				(width 0.05)
				(type default)
			)
			(fill no)
			(layer "F.CrtYd")
		)
		(pad "1" smd circle
			(at 0 0)
			(size 0.75 0.75)
			(layers "F.Cu" "F.Mask")
			(net 2 "GND")
			(pinfunction "1")
			(pintype "passive")
		)
	)
	(footprint "antmicro-footprints:R_0402_1005Metric"
		(layer "F.Cu")
		(at 95.8 80.3 90)
		(descr "Resistor SMD 0402")
		(tags "resistor SMD 0402")
		(property "Reference" "R8"
			(at -1.8689 7.0514 180)
			(layer "B.SilkS")
			(effects
				(font
					(size 0.7 0.7)
					(thickness 0.15)
				)
				(justify left bottom mirror)
			)
		)
		(property "Value" "R_100k_0402"
			(at -1.011843 1.772047 90)
			(layer "F.Fab")
			(effects
				(font
					(size 0.7 0.7)
					(thickness 0.15)
				)
				(justify left bottom)
			)
		)
		(property "Datasheet" "https://www.bourns.com/docs/product-datasheets/cr.pdf"
			(at 0 0 90)
			(layer "F.Fab")
			(hide yes)
			(effects
				(font
					(size 1.27 1.27)
					(thickness 0.15)
				)
			)
		)
		(property "Description" "SMD Chip Resistor, 100 kohm, ± 1%, 62.5 mW, 0402 [1005 Metric], Thick Film, General Purpose"
			(at 0 0 90)
			(layer "F.Fab")
			(hide yes)
			(effects
				(font
					(size 1.27 1.27)
					(thickness 0.15)
				)
			)
		)
		(property "Manufacturer" "Bourns"
			(at 0 0 90)
			(unlocked yes)
			(layer "F.Fab")
			(hide yes)
			(effects
				(font
					(size 1 1)
					(thickness 0.15)
				)
			)
		)
		(property "MPN" "CR0402-FX-1003GLF"
			(at 0 0 90)
			(unlocked yes)
			(layer "F.Fab")
			(hide yes)
			(effects
				(font
					(size 1 1)
					(thickness 0.15)
				)
			)
		)
		(property "Val" "100k"
			(at 0 0 90)
			(unlocked yes)
			(layer "F.Fab")
			(hide yes)
			(effects
				(font
					(size 1 1)
					(thickness 0.15)
				)
			)
		)
		(property "License" "Apache-2.0"
			(at 0 0 90)
			(unlocked yes)
			(layer "F.Fab")
			(hide yes)
			(effects
				(font
					(size 1 1)
					(thickness 0.15)
				)
			)
		)
		(property "Author" "Antmicro"
			(at 0 0 90)
			(unlocked yes)
			(layer "F.Fab")
			(hide yes)
			(effects
				(font
					(size 1 1)
					(thickness 0.15)
				)
			)
		)
		(property "Tolerance" "1%"
			(at 0 0 90)
			(unlocked yes)
			(layer "F.Fab")
			(hide yes)
			(effects
				(font
					(size 1 1)
					(thickness 0.15)
				)
			)
		)
		(sheetname "/DC-DC Converters/")
		(sheetfile "dc-dc_converters.kicad_sch")
		(attr smd)
		(fp_rect
			(start -0.925 -0.47)
			(end 0.925 0.47)
			(stroke
				(width 0.05)
				(type default)
			)
			(fill no)
			(layer "F.CrtYd")
		)
		(fp_rect
			(start -0.5 -0.25)
			(end 0.5 0.25)
			(stroke
				(width 0.15)
				(type solid)
			)
			(fill no)
			(layer "F.Fab")
		)
		(pad "1" smd roundrect
			(at -0.48 0 90)
			(size 0.59 0.64)
			(layers "F.Cu" "F.Mask" "F.Paste")
			(roundrect_rratio 0.25)
			(net 45 "Net-(U2-EN)")
			(pintype "passive")
		)
		(pad "2" smd roundrect
			(at 0.48 0 90)
			(size 0.59 0.64)
			(layers "F.Cu" "F.Mask" "F.Paste")
			(roundrect_rratio 0.25)
			(net 12 "Net-(U2-V_{CIN})")
			(pintype "passive")
		)
	)
)
